(kicad_pcb
	(version 20260206)
	(generator "pcbnew")
	(generator_version "10.0")
	(general
		(thickness 1.6)
		(legacy_teardrops no)
	)
	(paper "A4")
	(title_block
		(title "4HDD Backplane_Layout.brd")
		(comment 1 "Tioga Pass / footprints 9-15 of 97")
	)
	(layers
		(0 "F.Cu" signal "TOP")
		(4 "In1.Cu" signal "L2GND")
		(6 "In2.Cu" signal "L3")
		(8 "In3.Cu" signal "L4")
		(10 "In4.Cu" signal "L5GND")
		(2 "B.Cu" signal "BOTTOM")
		(9 "F.Adhes" user "F.Adhesive")
		(11 "B.Adhes" user "B.Adhesive")
		(13 "F.Paste" user "Package Geometry/Pastemask Top")
		(15 "B.Paste" user "Package Geometry/Pastemask Bottom")
		(5 "F.SilkS" user "Ref Des/Silkscreen Top")
		(7 "B.SilkS" user "Ref Des/Silkscreen Bottom")
		(1 "F.Mask" user "Board Geometry/Soldermask Top")
		(3 "B.Mask" user "Board Geometry/Soldermask Bottom")
		(17 "Dwgs.User" user "User.Drawings")
		(19 "Cmts.User" user "User.Comments")
		(21 "Eco1.User" user "User.Eco1")
		(23 "Eco2.User" user "User.Eco2")
		(25 "Edge.Cuts" user "Board Geometry/Outline")
		(27 "Margin" user)
		(31 "F.CrtYd" user "Package Geometry/Place Bound Top")
		(29 "B.CrtYd" user "Package Geometry/Place Bound Bottom")
		(35 "F.Fab" user "Ref Des/Assembly Top")
		(33 "B.Fab" user "Ref Des/Assembly Bottom")
	)
	(footprint ""
		(layer "F.Cu")
		(at 60.694824 -10.667746 90)
		(property "Reference" "C23"
			(at 0 0 90)
			(layer "F.SilkS")
			(hide yes)
			(effects
				(font
					(size 1.27 1.27)
				)
			)
		)
		(property "Value" "SC10U25V6KX-1GP"
			(at -0.0762 -5.1308 90)
			(unlocked yes)
			(layer "F.Fab")
			(hide yes)
			(effects
				(font
					(size 1.016 1.016)
					(thickness 0.1524)
				)
			)
		)
		(property "Device Type" "C1206H71"
			(at -0.127 -6.6548 90)
			(unlocked yes)
			(layer "F.Fab")
			(hide yes)
			(effects
				(font
					(size 1.016 1.016)
					(thickness 0.1524)
				)
			)
		)
		(duplicate_pad_numbers_are_jumpers no)
		(fp_line
			(start 1.016 -2.2352)
			(end 1.016 -0.8382)
			(stroke
				(width 0.1524)
				(type default)
			)
			(layer "F.SilkS")
		)
		(fp_line
			(start -1.016 -2.2352)
			(end 1.016 -2.2352)
			(stroke
				(width 0.1524)
				(type default)
			)
			(layer "F.SilkS")
		)
		(fp_line
			(start -1.016 -0.8382)
			(end -1.016 -2.2352)
			(stroke
				(width 0.1524)
				(type default)
			)
			(layer "F.SilkS")
		)
		(fp_line
			(start 1.016 0.8382)
			(end 1.016 2.2352)
			(stroke
				(width 0.1524)
				(type default)
			)
			(layer "F.SilkS")
		)
		(fp_line
			(start 1.016 2.2352)
			(end -1.016 2.2352)
			(stroke
				(width 0.1524)
				(type default)
			)
			(layer "F.SilkS")
		)
		(fp_line
			(start -1.016 2.2352)
			(end -1.016 0.8382)
			(stroke
				(width 0.1524)
				(type default)
			)
			(layer "F.SilkS")
		)
		(fp_rect
			(start -1.0922 2.3114)
			(end 1.0922 -2.3114)
			(stroke
				(width 0)
				(type default)
			)
			(fill no)
			(layer "F.CrtYd")
		)
		(fp_poly
			(pts
				(xy 1.0922 -2.3114) (xy 1.0922 2.3114) (xy -1.0922 2.3114) (xy -1.0922 -2.3114)
			)
			(stroke
				(width 0)
				(type default)
			)
			(fill no)
			(layer "F.Fab")
		)
		(pad "1" smd rect
			(at 0 -1.397 90)
			(size 1.651 1.27)
			(layers "F.Cu" "F.Mask" "F.Paste")
			(net "P12V_SW_L")
		)
		(pad "2" smd rect
			(at 0 1.397 90)
			(size 1.651 1.27)
			(layers "F.Cu" "F.Mask" "F.Paste")
			(net "GND")
		)
	)
	(footprint ""
		(layer "F.Cu")
		(at 77.724 -50.927 -90)
		(property "Reference" "C5"
			(at 0 0 270)
			(layer "F.SilkS")
			(hide yes)
			(effects
				(font
					(size 1.27 1.27)
				)
			)
		)
		(property "Value" "SC10U10V5KX-L1-GP"
			(at -0.0762 -6.1214 270)
			(unlocked yes)
			(layer "F.Fab")
			(hide yes)
			(effects
				(font
					(size 1.016 1.016)
					(thickness 0.1524)
				)
			)
		)
		(property "Device Type" "C805H58"
			(at -0.0762 -8.1534 270)
			(unlocked yes)
			(layer "F.Fab")
			(hide yes)
			(effects
				(font
					(size 1.016 1.016)
					(thickness 0.1524)
				)
			)
		)
		(duplicate_pad_numbers_are_jumpers no)
		(fp_line
			(start 0.635 0)
			(end -0.635 0)
			(stroke
				(width 0.508)
				(type default)
			)
			(layer "F.SilkS")
		)
		(fp_rect
			(start -0.9652 1.778)
			(end 0.9652 -1.778)
			(stroke
				(width 0)
				(type default)
			)
			(fill no)
			(layer "F.CrtYd")
		)
		(fp_poly
			(pts
				(xy -0.9652 -1.778) (xy 0.9652 -1.778) (xy 0.9652 1.778) (xy -0.9652 1.778)
			)
			(stroke
				(width 0)
				(type default)
			)
			(fill no)
			(layer "F.Fab")
		)
		(pad "1" smd rect
			(at 0 -0.9652 270)
			(size 1.397 1.143)
			(layers "F.Cu" "F.Mask" "F.Paste")
			(net "P5V_SW_R")
		)
		(pad "2" smd rect
			(at 0 0.9652 270)
			(size 1.397 1.143)
			(layers "F.Cu" "F.Mask" "F.Paste")
			(net "GND")
		)
	)
	(footprint ""
		(layer "F.Cu")
		(at 59.46902 -21.733256 90)
		(property "Reference" "C20"
			(at 0 0 90)
			(layer "F.SilkS")
			(hide yes)
			(effects
				(font
					(size 1.27 1.27)
				)
			)
		)
		(property "Value" "SC10U25V6KX-1GP"
			(at -0.0762 -5.1308 90)
			(unlocked yes)
			(layer "F.Fab")
			(hide yes)
			(effects
				(font
					(size 1.016 1.016)
					(thickness 0.1524)
				)
			)
		)
		(property "Device Type" "C1206H71"
			(at -0.127 -6.6548 90)
			(unlocked yes)
			(layer "F.Fab")
			(hide yes)
			(effects
				(font
					(size 1.016 1.016)
					(thickness 0.1524)
				)
			)
		)
		(duplicate_pad_numbers_are_jumpers no)
		(fp_line
			(start 1.016 -2.2352)
			(end 1.016 -0.8382)
			(stroke
				(width 0.1524)
				(type default)
			)
			(layer "F.SilkS")
		)
		(fp_line
			(start -1.016 -2.2352)
			(end 1.016 -2.2352)
			(stroke
				(width 0.1524)
				(type default)
			)
			(layer "F.SilkS")
		)
		(fp_line
			(start -1.016 -0.8382)
			(end -1.016 -2.2352)
			(stroke
				(width 0.1524)
				(type default)
			)
			(layer "F.SilkS")
		)
		(fp_line
			(start 1.016 0.8382)
			(end 1.016 2.2352)
			(stroke
				(width 0.1524)
				(type default)
			)
			(layer "F.SilkS")
		)
		(fp_line
			(start 1.016 2.2352)
			(end -1.016 2.2352)
			(stroke
				(width 0.1524)
				(type default)
			)
			(layer "F.SilkS")
		)
		(fp_line
			(start -1.016 2.2352)
			(end -1.016 0.8382)
			(stroke
				(width 0.1524)
				(type default)
			)
			(layer "F.SilkS")
		)
		(fp_rect
			(start -1.0922 2.3114)
			(end 1.0922 -2.3114)
			(stroke
				(width 0)
				(type default)
			)
			(fill no)
			(layer "F.CrtYd")
		)
		(fp_poly
			(pts
				(xy 1.0922 -2.3114) (xy 1.0922 2.3114) (xy -1.0922 2.3114) (xy -1.0922 -2.3114)
			)
			(stroke
				(width 0)
				(type default)
			)
			(fill no)
			(layer "F.Fab")
		)
		(pad "1" smd rect
			(at 0 -1.397 90)
			(size 1.651 1.27)
			(layers "F.Cu" "F.Mask" "F.Paste")
			(net "P12V_SW_L")
		)
		(pad "2" smd rect
			(at 0 1.397 90)
			(size 1.651 1.27)
			(layers "F.Cu" "F.Mask" "F.Paste")
			(net "GND")
		)
	)
	(footprint ""
		(layer "F.Cu")
		(at 121.8946 -57.277 180)
		(property "Reference" "C3"
			(at 0 0 180)
			(layer "F.SilkS")
			(hide yes)
			(effects
				(font
					(size 1.27 1.27)
				)
			)
		)
		(property "Value" "SCD01U50V2KX-1GP"
			(at 1.1811 -2.7051 180)
			(unlocked yes)
			(layer "F.Fab")
			(hide yes)
			(effects
				(font
					(size 1.016 1.016)
					(thickness 0.1524)
				)
			)
		)
		(property "Device Type" "C402H22"
			(at 1.1811 -4.2291 180)
			(unlocked yes)
			(layer "F.Fab")
			(hide yes)
			(effects
				(font
					(size 1.016 1.016)
					(thickness 0.1524)
				)
			)
		)
		(duplicate_pad_numbers_are_jumpers no)
		(fp_rect
			(start -0.4318 0.9525)
			(end 0.4318 -0.9525)
			(stroke
				(width 0)
				(type default)
			)
			(fill no)
			(layer "F.CrtYd")
		)
		(fp_rect
			(start -0.4318 0.9525)
			(end 0.4318 -0.9525)
			(stroke
				(width 0)
				(type default)
			)
			(fill no)
			(layer "F.Fab")
		)
		(pad "1" smd custom
			(at 0 -0.4445 180)
			(size 0.1524 0.1524)
			(layers "F.Cu" "F.Mask" "F.Paste")
			(net "HBA_PRSNT0_N")
			(options
				(clearance outline)
				(anchor circle)
			)
			(primitives
				(gr_poly
					(pts
						(arc
							(start 0.3048 -0.2032)
							(mid 0.275042 -0.275042)
							(end 0.2032 -0.3048)
						)
						(arc
							(start -0.2032 -0.3048)
							(mid -0.275042 -0.275042)
							(end -0.3048 -0.2032)
						)
						(arc
							(start -0.3048 0.2032)
							(mid -0.275042 0.275042)
							(end -0.2032 0.3048)
						)
						(arc
							(start 0.2032 0.3048)
							(mid 0.275042 0.275042)
							(end 0.3048 0.2032)
						)
					)
					(width 0)
					(fill yes)
				)
			)
		)
		(pad "2" smd custom
			(at 0 0.4445 180)
			(size 0.1524 0.1524)
			(layers "F.Cu" "F.Mask" "F.Paste")
			(net "GND")
			(options
				(clearance outline)
				(anchor circle)
			)
			(primitives
				(gr_poly
					(pts
						(arc
							(start 0.3048 -0.2032)
							(mid 0.275042 -0.275042)
							(end 0.2032 -0.3048)
						)
						(arc
							(start -0.2032 -0.3048)
							(mid -0.275042 -0.275042)
							(end -0.3048 -0.2032)
						)
						(arc
							(start -0.3048 0.2032)
							(mid -0.275042 0.275042)
							(end -0.2032 0.3048)
						)
						(arc
							(start 0.2032 0.3048)
							(mid 0.275042 0.275042)
							(end 0.3048 0.2032)
						)
					)
					(width 0)
					(fill yes)
				)
			)
		)
	)
	(footprint ""
		(layer "F.Cu")
		(at 89.027 -7.493 90)
		(property "Reference" "R146"
			(at 0 0 90)
			(layer "F.SilkS")
			(hide yes)
			(effects
				(font
					(size 1.27 1.27)
				)
			)
		)
		(property "Value" "4K7R2J-2-GP"
			(at 0.064008 -3.993896 90)
			(unlocked yes)
			(layer "F.Fab")
			(hide yes)
			(effects
				(font
					(size 1.016 1.016)
					(thickness 0.1524)
				)
			)
		)
		(property "Device Type" "R402H16"
			(at 0.064008 -5.517896 90)
			(unlocked yes)
			(layer "F.Fab")
			(hide yes)
			(effects
				(font
					(size 1.016 1.016)
					(thickness 0.1524)
				)
			)
		)
		(duplicate_pad_numbers_are_jumpers no)
		(fp_line
			(start 0.508 -0.9398)
			(end -0.508 -0.9398)
			(stroke
				(width 0.1524)
				(type default)
			)
			(layer "F.SilkS")
		)
		(fp_line
			(start -0.508 -0.9398)
			(end -0.508 0.9398)
			(stroke
				(width 0.1524)
				(type default)
			)
			(layer "F.SilkS")
		)
		(fp_rect
			(start -0.508 0.9398)
			(end 0.508 -0.9398)
			(stroke
				(width 0)
				(type default)
			)
			(fill no)
			(layer "F.CrtYd")
		)
		(fp_rect
			(start -0.508 0.9398)
			(end 0.508 -0.9398)
			(stroke
				(width 0)
				(type default)
			)
			(fill no)
			(layer "F.Fab")
		)
		(pad "1" smd custom
			(at 0 -0.4445 90)
			(size 0.1397 0.1397)
			(layers "F.Cu" "F.Mask" "F.Paste")
			(net "P12V")
			(options
				(clearance outline)
				(anchor circle)
			)
			(primitives
				(gr_poly
					(pts
						(arc
							(start -0.1778 -0.2794)
							(mid -0.249642 -0.249642)
							(end -0.2794 -0.1778)
						)
						(arc
							(start -0.2794 0.1778)
							(mid -0.249642 0.249642)
							(end -0.1778 0.2794)
						)
						(arc
							(start 0.1778 0.2794)
							(mid 0.249642 0.249642)
							(end 0.2794 0.1778)
						)
						(arc
							(start 0.2794 -0.1778)
							(mid 0.249642 -0.249642)
							(end 0.1778 -0.2794)
						)
					)
					(width 0)
					(fill yes)
				)
			)
		)
		(pad "2" smd custom
			(at 0 0.4445 90)
			(size 0.1397 0.1397)
			(layers "F.Cu" "F.Mask" "F.Paste")
			(net "SW_SW_L_0")
			(options
				(clearance outline)
				(anchor circle)
			)
			(primitives
				(gr_poly
					(pts
						(arc
							(start -0.1778 -0.2794)
							(mid -0.249642 -0.249642)
							(end -0.2794 -0.1778)
						)
						(arc
							(start -0.2794 0.1778)
							(mid -0.249642 0.249642)
							(end -0.1778 0.2794)
						)
						(arc
							(start 0.1778 0.2794)
							(mid 0.249642 0.249642)
							(end 0.2794 0.1778)
						)
						(arc
							(start 0.2794 -0.1778)
							(mid 0.249642 -0.249642)
							(end 0.1778 -0.2794)
						)
					)
					(width 0)
					(fill yes)
				)
			)
		)
	)
	(footprint ""
		(layer "F.Cu")
		(at 56.884824 -9.727946 -90)
		(property "Reference" "C24"
			(at 0 0 270)
			(layer "F.SilkS")
			(hide yes)
			(effects
				(font
					(size 1.27 1.27)
				)
			)
		)
		(property "Value" "SCD1U25V2KX-GP"
			(at 1.1811 -2.7051 270)
			(unlocked yes)
			(layer "F.Fab")
			(hide yes)
			(effects
				(font
					(size 1.016 1.016)
					(thickness 0.1524)
				)
			)
		)
		(property "Device Type" "C402H22"
			(at 1.1811 -4.2291 270)
			(unlocked yes)
			(layer "F.Fab")
			(hide yes)
			(effects
				(font
					(size 1.016 1.016)
					(thickness 0.1524)
				)
			)
		)
		(duplicate_pad_numbers_are_jumpers no)
		(fp_rect
			(start -0.4318 0.9525)
			(end 0.4318 -0.9525)
			(stroke
				(width 0)
				(type default)
			)
			(fill no)
			(layer "F.CrtYd")
		)
		(fp_rect
			(start -0.4318 0.9525)
			(end 0.4318 -0.9525)
			(stroke
				(width 0)
				(type default)
			)
			(fill no)
			(layer "F.Fab")
		)
		(pad "1" smd custom
			(at 0 -0.4445 270)
			(size 0.1524 0.1524)
			(layers "F.Cu" "F.Mask" "F.Paste")
			(net "P12V_SW_L")
			(options
				(clearance outline)
				(anchor circle)
			)
			(primitives
				(gr_poly
					(pts
						(arc
							(start 0.3048 -0.2032)
							(mid 0.275042 -0.275042)
							(end 0.2032 -0.3048)
						)
						(arc
							(start -0.2032 -0.3048)
							(mid -0.275042 -0.275042)
							(end -0.3048 -0.2032)
						)
						(arc
							(start -0.3048 0.2032)
							(mid -0.275042 0.275042)
							(end -0.2032 0.3048)
						)
						(arc
							(start 0.2032 0.3048)
							(mid 0.275042 0.275042)
							(end 0.3048 0.2032)
						)
					)
					(width 0)
					(fill yes)
				)
			)
		)
		(pad "2" smd custom
			(at 0 0.4445 270)
			(size 0.1524 0.1524)
			(layers "F.Cu" "F.Mask" "F.Paste")
			(net "GND")
			(options
				(clearance outline)
				(anchor circle)
			)
			(primitives
				(gr_poly
					(pts
						(arc
							(start 0.3048 -0.2032)
							(mid 0.275042 -0.275042)
							(end 0.2032 -0.3048)
						)
						(arc
							(start -0.2032 -0.3048)
							(mid -0.275042 -0.275042)
							(end -0.3048 -0.2032)
						)
						(arc
							(start -0.3048 0.2032)
							(mid -0.275042 0.275042)
							(end -0.2032 0.3048)
						)
						(arc
							(start 0.2032 0.3048)
							(mid 0.275042 0.275042)
							(end 0.3048 0.2032)
						)
					)
					(width 0)
					(fill yes)
				)
			)
		)
	)
	(footprint ""
		(layer "F.Cu")
		(at 80.01 -8.128 90)
		(property "Reference" "R154"
			(at 0 0 90)
			(layer "F.SilkS")
			(hide yes)
			(effects
				(font
					(size 1.27 1.27)
				)
			)
		)
		(property "Value" "10KR2J-3-GP"
			(at 0.064008 -3.993896 90)
			(unlocked yes)
			(layer "F.Fab")
			(hide yes)
			(effects
				(font
					(size 1.016 1.016)
					(thickness 0.1524)
				)
			)
		)
		(property "Device Type" "R402H16"
			(at 0.064008 -5.517896 90)
			(unlocked yes)
			(layer "F.Fab")
			(hide yes)
			(effects
				(font
					(size 1.016 1.016)
					(thickness 0.1524)
				)
			)
		)
		(duplicate_pad_numbers_are_jumpers no)
		(fp_line
			(start 0.508 -0.9398)
			(end -0.508 -0.9398)
			(stroke
				(width 0.1524)
				(type default)
			)
			(layer "F.SilkS")
		)
		(fp_line
			(start -0.508 -0.9398)
			(end -0.508 0.9398)
			(stroke
				(width 0.1524)
				(type default)
			)
			(layer "F.SilkS")
		)
		(fp_rect
			(start -0.508 0.9398)
			(end 0.508 -0.9398)
			(stroke
				(width 0)
				(type default)
			)
			(fill no)
			(layer "F.CrtYd")
		)
		(fp_rect
			(start -0.508 0.9398)
			(end 0.508 -0.9398)
			(stroke
				(width 0)
				(type default)
			)
			(fill no)
			(layer "F.Fab")
		)
		(pad "1" smd custom
			(at 0 -0.4445 90)
			(size 0.1397 0.1397)
			(layers "F.Cu" "F.Mask" "F.Paste")
			(net "VIN_P3")
			(options
				(clearance outline)
				(anchor circle)
			)
			(primitives
				(gr_poly
					(pts
						(arc
							(start -0.1778 -0.2794)
							(mid -0.249642 -0.249642)
							(end -0.2794 -0.1778)
						)
						(arc
							(start -0.2794 0.1778)
							(mid -0.249642 0.249642)
							(end -0.1778 0.2794)
						)
						(arc
							(start 0.1778 0.2794)
							(mid 0.249642 0.249642)
							(end 0.2794 0.1778)
						)
						(arc
							(start 0.2794 -0.1778)
							(mid 0.249642 -0.249642)
							(end 0.1778 -0.2794)
						)
					)
					(width 0)
					(fill yes)
				)
			)
		)
		(pad "2" smd custom
			(at 0 0.4445 90)
			(size 0.1397 0.1397)
			(layers "F.Cu" "F.Mask" "F.Paste")
			(net "GND")
			(options
				(clearance outline)
				(anchor circle)
			)
			(primitives
				(gr_poly
					(pts
						(arc
							(start -0.1778 -0.2794)
							(mid -0.249642 -0.249642)
							(end -0.2794 -0.1778)
						)
						(arc
							(start -0.2794 0.1778)
							(mid -0.249642 0.249642)
							(end -0.1778 0.2794)
						)
						(arc
							(start 0.1778 0.2794)
							(mid 0.249642 0.249642)
							(end 0.2794 0.1778)
						)
						(arc
							(start 0.2794 -0.1778)
							(mid 0.249642 -0.249642)
							(end 0.1778 -0.2794)
						)
					)
					(width 0)
					(fill yes)
				)
			)
		)
	)
)
